# T6G (Grand Teton) — schematic netlist excerpt (pin names and nets, part order shuffled) for the footprints in the layout excerpt that follows; sources: Cadence DE-HDL packaged netlist, KiCad conversion of 04192023_DAF0TMB3IC0_F0TG_MB_C_brd_V02_OCP.brd

PR253  Q_RES  1 1% CHIP  pkg 0402LF  page 217 : A = PVDDCR_CPU1_P1_VCC ; B = P3V3_AUX
C564  Q_CAP  100UF 4V 20% X6S  pkg C0805  page 279 : A = P0V9_CPU0_RT0_2A ; B = GND
PR3916  Q_RES  0 5% CHIP  pkg 0402LF  page 263 : A = HSC_SCREF ; B = HSC_SCREF_1

(kicad_pcb
	(version 20260206)
	(generator "pcbnew")
	(generator_version "10.0")
	(general
		(thickness 1.6)
		(legacy_teardrops no)
	)
	(paper "A4")
	(title_block
		(title "04192023_DAF0TMB3IC0_F0TG_MB_C_brd_V02_OCP.brd")
		(comment 1 "Grand Teton / footprints 2317-2319 of 8354")
	)
	(layers
		(0 "F.Cu" signal "TOP")
		(4 "In1.Cu" signal "GND")
		(6 "In2.Cu" signal "IN1")
		(8 "In3.Cu" signal "GND1")
		(10 "In4.Cu" signal "IN2")
		(12 "In5.Cu" signal "GND2")
		(14 "In6.Cu" signal "IN3")
		(16 "In7.Cu" signal "GND3")
		(18 "In8.Cu" signal "VCC")
		(20 "In9.Cu" signal "VCC1")
		(22 "In10.Cu" signal "GND4")
		(24 "In11.Cu" signal "IN4")
		(26 "In12.Cu" signal "GND5")
		(28 "In13.Cu" signal "IN5")
		(30 "In14.Cu" signal "GND6")
		(32 "In15.Cu" signal "IN6")
		(34 "In16.Cu" signal "GND7")
		(2 "B.Cu" signal "BOTTOM")
		(9 "F.Adhes" user "F.Adhesive")
		(11 "B.Adhes" user "B.Adhesive")
		(13 "F.Paste" user "Package Geometry/Pastemask Top")
		(15 "B.Paste" user "Package Geometry/Pastemask Bottom")
		(5 "F.SilkS" user "Ref Des/Silkscreen Top")
		(7 "B.SilkS" user "Ref Des/Silkscreen Bottom")
		(1 "F.Mask" user "Board Geometry/Soldermask Top")
		(3 "B.Mask" user "Board Geometry/Soldermask Bottom")
		(17 "Dwgs.User" user "User.Drawings")
		(19 "Cmts.User" user "User.Comments")
		(21 "Eco1.User" user "User.Eco1")
		(23 "Eco2.User" user "User.Eco2")
		(25 "Edge.Cuts" user "Board Geometry/Outline")
		(27 "Margin" user)
		(31 "F.CrtYd" user "Package Geometry/Place Bound Top")
		(29 "B.CrtYd" user "Package Geometry/Place Bound Bottom")
		(35 "F.Fab" user "Ref Des/Assembly Top")
		(33 "B.Fab" user "Ref Des/Assembly Bottom")
	)
	(footprint ""
		(layer "F.Cu")
		(at 37.853112 -368.455448 90)
		(property "Reference" "PR253"
			(at 0 0 90)
			(layer "F.SilkS")
			(hide yes)
			(effects
				(font
					(size 1.27 1.27)
				)
			)
		)
		(property "Value" ""
			(at 0 0 90)
			(layer "F.Fab")
			(effects
				(font
					(size 1.27 1.27)
				)
			)
		)
		(duplicate_pad_numbers_are_jumpers no)
		(fp_line
			(start 0.7874 -0.4064)
			(end 0.7874 0.4064)
			(stroke
				(width 0.1524)
				(type default)
			)
			(layer "F.SilkS")
		)
		(fp_line
			(start -0.7874 -0.4064)
			(end 0.7874 -0.4064)
			(stroke
				(width 0.1524)
				(type default)
			)
			(layer "F.SilkS")
		)
		(fp_line
			(start 0.7874 0.4064)
			(end -0.7874 0.4064)
			(stroke
				(width 0.1524)
				(type default)
			)
			(layer "F.SilkS")
		)
		(fp_line
			(start -0.7874 0.4064)
			(end -0.7874 -0.4064)
			(stroke
				(width 0.1524)
				(type default)
			)
			(layer "F.SilkS")
		)
		(fp_line
			(start -0.12065 -0.305054)
			(end -0.12065 -0.2794)
			(stroke
				(width 0.1)
				(type default)
			)
			(layer "F.Fab")
		)
		(fp_line
			(start -0.67945 -0.305054)
			(end -0.12065 -0.305054)
			(stroke
				(width 0.1)
				(type default)
			)
			(layer "F.Fab")
		)
		(fp_line
			(start 0.67945 -0.3048)
			(end 0.67945 0.3048)
			(stroke
				(width 0.1)
				(type default)
			)
			(layer "F.Fab")
		)
		(fp_line
			(start 0.12065 -0.3048)
			(end 0.67945 -0.3048)
			(stroke
				(width 0.1)
				(type default)
			)
			(layer "F.Fab")
		)
		(fp_line
			(start 0.12065 -0.2794)
			(end 0.12065 -0.3048)
			(stroke
				(width 0.1)
				(type default)
			)
			(layer "F.Fab")
		)
		(fp_line
			(start -0.12065 -0.2794)
			(end 0.12065 -0.2794)
			(stroke
				(width 0.1)
				(type default)
			)
			(layer "F.Fab")
		)
		(fp_line
			(start 0.120396 0.2794)
			(end -0.12065 0.2794)
			(stroke
				(width 0.1)
				(type default)
			)
			(layer "F.Fab")
		)
		(fp_line
			(start -0.12065 0.2794)
			(end -0.12065 0.3048)
			(stroke
				(width 0.1)
				(type default)
			)
			(layer "F.Fab")
		)
		(fp_line
			(start 0.67945 0.3048)
			(end 0.120396 0.3048)
			(stroke
				(width 0.1)
				(type default)
			)
			(layer "F.Fab")
		)
		(fp_line
			(start 0.120396 0.3048)
			(end 0.120396 0.2794)
			(stroke
				(width 0.1)
				(type default)
			)
			(layer "F.Fab")
		)
		(fp_line
			(start -0.12065 0.3048)
			(end -0.67945 0.3048)
			(stroke
				(width 0.1)
				(type default)
			)
			(layer "F.Fab")
		)
		(fp_line
			(start -0.67945 0.3048)
			(end -0.67945 -0.305054)
			(stroke
				(width 0.1)
				(type default)
			)
			(layer "F.Fab")
		)
		(pad "1" smd circle
			(at -0.40005 0 90)
			(size 0 0)
			(layers "F.Cu" "F.Mask" "F.Paste")
			(net "PVDDCR_CPU1_P1_VCC")
		)
		(pad "2" smd circle
			(at 0.40005 0 90)
			(size 0 0)
			(layers "F.Cu" "F.Mask" "F.Paste")
			(net "P3V3_AUX")
		)
	)
	(footprint ""
		(layer "F.Cu")
		(at 303.868328 -404.392892)
		(property "Reference" "C564"
			(at 0 0 0)
			(layer "F.SilkS")
			(hide yes)
			(effects
				(font
					(size 1.27 1.27)
				)
			)
		)
		(property "Value" ""
			(at 0 0 0)
			(layer "F.Fab")
			(effects
				(font
					(size 1.27 1.27)
				)
			)
		)
		(duplicate_pad_numbers_are_jumpers no)
		(fp_line
			(start -1.524 -0.762)
			(end 1.524 -0.762)
			(stroke
				(width 0.1524)
				(type default)
			)
			(layer "F.SilkS")
		)
		(fp_line
			(start -1.524 0.762)
			(end -1.524 -0.762)
			(stroke
				(width 0.1524)
				(type default)
			)
			(layer "F.SilkS")
		)
		(fp_line
			(start 1.524 -0.762)
			(end 1.524 0.762)
			(stroke
				(width 0.1524)
				(type default)
			)
			(layer "F.SilkS")
		)
		(fp_line
			(start 1.524 0.762)
			(end -1.524 0.762)
			(stroke
				(width 0.1524)
				(type default)
			)
			(layer "F.SilkS")
		)
		(fp_line
			(start -1.1049 -0.724916)
			(end -1.1049 0.724916)
			(stroke
				(width 0.1)
				(type default)
			)
			(layer "F.Fab")
		)
		(fp_line
			(start -1.1049 0.724916)
			(end 1.1049 0.724916)
			(stroke
				(width 0.1)
				(type default)
			)
			(layer "F.Fab")
		)
		(fp_line
			(start 1.1049 -0.724916)
			(end -1.1049 -0.724916)
			(stroke
				(width 0.1)
				(type default)
			)
			(layer "F.Fab")
		)
		(fp_line
			(start 1.1049 0.724916)
			(end 1.1049 -0.724916)
			(stroke
				(width 0.1)
				(type default)
			)
			(layer "F.Fab")
		)
		(pad "1" smd rect
			(at -0.889 0 180)
			(size 1.016 1.27)
			(layers "F.Cu" "F.Mask" "F.Paste")
			(net "P0V9_CPU0_RT0_2A")
		)
		(pad "2" smd rect
			(at 0.889 0 180)
			(size 1.016 1.27)
			(layers "F.Cu" "F.Mask" "F.Paste")
			(net "GND")
		)
	)
	(footprint ""
		(layer "F.Cu")
		(at 194.2211 -404.300182)
		(property "Reference" "PR3916"
			(at 0 0 0)
			(layer "F.SilkS")
			(hide yes)
			(effects
				(font
					(size 1.27 1.27)
				)
			)
		)
		(property "Value" ""
			(at 0 0 0)
			(layer "F.Fab")
			(effects
				(font
					(size 1.27 1.27)
				)
			)
		)
		(duplicate_pad_numbers_are_jumpers no)
		(fp_line
			(start -0.7874 -0.4064)
			(end 0.7874 -0.4064)
			(stroke
				(width 0.1524)
				(type default)
			)
			(layer "F.SilkS")
		)
		(fp_line
			(start -0.7874 0.4064)
			(end -0.7874 -0.4064)
			(stroke
				(width 0.1524)
				(type default)
			)
			(layer "F.SilkS")
		)
		(fp_line
			(start 0.7874 -0.4064)
			(end 0.7874 0.4064)
			(stroke
				(width 0.1524)
				(type default)
			)
			(layer "F.SilkS")
		)
		(fp_line
			(start 0.7874 0.4064)
			(end -0.7874 0.4064)
			(stroke
				(width 0.1524)
				(type default)
			)
			(layer "F.SilkS")
		)
		(fp_line
			(start -0.67945 -0.305054)
			(end -0.12065 -0.305054)
			(stroke
				(width 0.1)
				(type default)
			)
			(layer "F.Fab")
		)
		(fp_line
			(start -0.67945 0.3048)
			(end -0.67945 -0.305054)
			(stroke
				(width 0.1)
				(type default)
			)
			(layer "F.Fab")
		)
		(fp_line
			(start -0.12065 -0.305054)
			(end -0.12065 -0.2794)
			(stroke
				(width 0.1)
				(type default)
			)
			(layer "F.Fab")
		)
		(fp_line
			(start -0.12065 -0.2794)
			(end 0.12065 -0.2794)
			(stroke
				(width 0.1)
				(type default)
			)
			(layer "F.Fab")
		)
		(fp_line
			(start -0.12065 0.2794)
			(end -0.12065 0.3048)
			(stroke
				(width 0.1)
				(type default)
			)
			(layer "F.Fab")
		)
		(fp_line
			(start -0.12065 0.3048)
			(end -0.67945 0.3048)
			(stroke
				(width 0.1)
				(type default)
			)
			(layer "F.Fab")
		)
		(fp_line
			(start 0.120396 0.2794)
			(end -0.12065 0.2794)
			(stroke
				(width 0.1)
				(type default)
			)
			(layer "F.Fab")
		)
		(fp_line
			(start 0.120396 0.3048)
			(end 0.120396 0.2794)
			(stroke
				(width 0.1)
				(type default)
			)
			(layer "F.Fab")
		)
		(fp_line
			(start 0.12065 -0.3048)
			(end 0.67945 -0.3048)
			(stroke
				(width 0.1)
				(type default)
			)
			(layer "F.Fab")
		)
		(fp_line
			(start 0.12065 -0.2794)
			(end 0.12065 -0.3048)
			(stroke
				(width 0.1)
				(type default)
			)
			(layer "F.Fab")
		)
		(fp_line
			(start 0.67945 -0.3048)
			(end 0.67945 0.3048)
			(stroke
				(width 0.1)
				(type default)
			)
			(layer "F.Fab")
		)
		(fp_line
			(start 0.67945 0.3048)
			(end 0.120396 0.3048)
			(stroke
				(width 0.1)
				(type default)
			)
			(layer "F.Fab")
		)
		(pad "1" smd circle
			(at -0.40005 0)
			(size 0 0)
			(layers "F.Cu" "F.Mask" "F.Paste")
			(net "HSC_SCREF")
		)
		(pad "2" smd circle
			(at 0.40005 0)
			(size 0 0)
			(layers "F.Cu" "F.Mask" "F.Paste")
			(net "HSC_SCREF_1")
		)
	)
)
